(kicad_pcb
	(version 20260206)
	(generator "pcbnew")
	(generator_version "10.0")
	(general
		(thickness 1.6)
		(legacy_teardrops no)
	)
	(paper "A4")
	(title_block
		(title "Wiwynn_Tioga_Pass_MB.brd")
		(comment 1 "Tioga Pass / footprints 594-600 of 4770")
	)
	(layers
		(0 "F.Cu" signal "TOP")
		(4 "In1.Cu" signal "L2GND")
		(6 "In2.Cu" signal "L3")
		(8 "In3.Cu" signal "L4GND")
		(10 "In4.Cu" signal "L5")
		(12 "In5.Cu" signal "L6GND")
		(14 "In6.Cu" signal "L7VCC")
		(16 "In7.Cu" signal "L8VCC")
		(18 "In8.Cu" signal "L9GND")
		(20 "In9.Cu" signal "L10")
		(22 "In10.Cu" signal "L11GND")
		(24 "In11.Cu" signal "L12")
		(26 "In12.Cu" signal "L13GND")
		(2 "B.Cu" signal "BOTTOM")
		(9 "F.Adhes" user "F.Adhesive")
		(11 "B.Adhes" user "B.Adhesive")
		(13 "F.Paste" user "Package Geometry/Pastemask Top")
		(15 "B.Paste" user "Package Geometry/Pastemask Bottom")
		(5 "F.SilkS" user "Ref Des/Silkscreen Top")
		(7 "B.SilkS" user "Ref Des/Silkscreen Bottom")
		(1 "F.Mask" user "Board Geometry/Soldermask Top")
		(3 "B.Mask" user "Board Geometry/Soldermask Bottom")
		(17 "Dwgs.User" user "User.Drawings")
		(19 "Cmts.User" user "User.Comments")
		(21 "Eco1.User" user "User.Eco1")
		(23 "Eco2.User" user "User.Eco2")
		(25 "Edge.Cuts" user "Board Geometry/Outline")
		(27 "Margin" user)
		(31 "F.CrtYd" user "Package Geometry/Place Bound Top")
		(29 "B.CrtYd" user "Package Geometry/Place Bound Bottom")
		(35 "F.Fab" user "Ref Des/Assembly Top")
		(33 "B.Fab" user "Ref Des/Assembly Bottom")
	)
	(footprint ""
		(layer "F.Cu")
		(at 339.471 -21.209 90)
		(property "Reference" "R7F20"
			(at -0.8382 -0.67818 90)
			(unlocked yes)
			(layer "F.SilkS")
			(effects
				(font
					(size 0.4064 0.254)
					(thickness 0.1524)
				)
				(justify left)
			)
		)
		(property "Value" ""
			(at 0 0 90)
			(layer "F.Fab")
			(effects
				(font
					(size 1.27 1.27)
				)
			)
		)
		(duplicate_pad_numbers_are_jumpers no)
		(fp_poly
			(pts
				(xy -0.2794 -0.1016) (xy 0.2794 -0.1016) (xy 0.2794 0.9906) (xy -0.2794 0.9906)
			)
			(stroke
				(width 0)
				(type default)
			)
			(fill no)
			(layer "F.CrtYd")
		)
		(fp_line
			(start 0.2794 -0.1016)
			(end -0.2794 -0.1016)
			(stroke
				(width 0.1)
				(type default)
			)
			(layer "F.Fab")
		)
		(fp_line
			(start -0.2794 -0.1016)
			(end -0.2794 0.9906)
			(stroke
				(width 0.1)
				(type default)
			)
			(layer "F.Fab")
		)
		(fp_line
			(start 0.2794 0.9906)
			(end 0.2794 -0.1016)
			(stroke
				(width 0.1)
				(type default)
			)
			(layer "F.Fab")
		)
		(fp_line
			(start -0.2794 0.9906)
			(end 0.2794 0.9906)
			(stroke
				(width 0.1)
				(type default)
			)
			(layer "F.Fab")
		)
		(pad "1" smd rect
			(at 0 0 90)
			(size 0.508 0.508)
			(layers "F.Cu" "F.Mask" "F.Paste")
			(net "P3V3_STBY")
		)
		(pad "2" smd rect
			(at 0 0.889 90)
			(size 0.508 0.508)
			(layers "F.Cu" "F.Mask" "F.Paste")
			(net "VR_PVDDQ_ABC_VREN")
		)
		(zone
			(layer "F.Cu")
			(hatch none 0.5)
			(connect_pads
				(clearance 0)
			)
			(min_thickness 0.25)
			(keepout
				(tracks allowed)
				(vias not_allowed)
				(pads allowed)
				(copperpour not_allowed)
				(footprints allowed)
			)
			(placement
				(enabled no)
				(sheetname "")
			)
			(fill
				(thermal_gap 0.5)
				(thermal_bridge_width 0.5)
				(island_removal_mode 0)
			)
			(polygon
				(pts
					(xy 339.725 -20.955) (xy 339.725 -21.463) (xy 340.106 -21.463) (xy 340.106 -20.955)
				)
			)
		)
		(zone
			(layer "F.Cu")
			(hatch none 0.5)
			(connect_pads
				(clearance 0)
			)
			(min_thickness 0.25)
			(keepout
				(tracks not_allowed)
				(vias allowed)
				(pads allowed)
				(copperpour not_allowed)
				(footprints allowed)
			)
			(placement
				(enabled no)
				(sheetname "")
			)
			(fill
				(thermal_gap 0.5)
				(thermal_bridge_width 0.5)
				(island_removal_mode 0)
			)
			(polygon
				(pts
					(xy 340.106 -20.955) (xy 340.106 -21.463) (xy 339.725 -21.463) (xy 339.725 -20.955)
				)
			)
		)
	)
	(footprint ""
		(layer "F.Cu")
		(at 35.86734 -93.897196 -90)
		(property "Reference" "RT38"
			(at 0 0 270)
			(layer "F.SilkS")
			(hide yes)
			(effects
				(font
					(size 1.27 1.27)
				)
			)
		)
		(property "Value" "*"
			(at -0.0254 -2.6289 270)
			(unlocked yes)
			(layer "F.Fab")
			(hide yes)
			(effects
				(font
					(size 1.27 1.016)
					(thickness 0.1524)
				)
			)
		)
		(property "Device Type" "1R3F-GP_RCL_GP-1R3F-GP,64.1R00A"
			(at -0.0254 -4.1529 270)
			(unlocked yes)
			(layer "F.Fab")
			(hide yes)
			(effects
				(font
					(size 1.27 1.016)
					(thickness 0.1524)
				)
			)
		)
		(duplicate_pad_numbers_are_jumpers no)
		(fp_line
			(start -0.4826 0)
			(end -0.2032 0)
			(stroke
				(width 0.2032)
				(type default)
			)
			(layer "F.SilkS")
		)
		(fp_line
			(start 0.2032 0)
			(end 0.4826 0)
			(stroke
				(width 0.2032)
				(type default)
			)
			(layer "F.SilkS")
		)
		(fp_rect
			(start -0.5842 1.3335)
			(end 0.5842 -1.3335)
			(stroke
				(width 0)
				(type default)
			)
			(fill no)
			(layer "F.CrtYd")
		)
		(fp_rect
			(start -0.5842 1.3335)
			(end 0.5842 -1.3335)
			(stroke
				(width 0)
				(type default)
			)
			(fill no)
			(layer "F.Fab")
		)
		(pad "1" smd custom
			(at 0 -0.762 270)
			(size 0.2159 0.2159)
			(layers "F.Cu" "F.Mask" "F.Paste")
			(net "VR_PVSA_CPU1_PHASE_SW_RC")
			(options
				(clearance outline)
				(anchor circle)
			)
			(primitives
				(gr_poly
					(pts
						(arc
							(start -0.3302 -0.4318)
							(mid -0.402042 -0.402042)
							(end -0.4318 -0.3302)
						)
						(arc
							(start -0.4318 0.3302)
							(mid -0.402042 0.402042)
							(end -0.3302 0.4318)
						)
						(arc
							(start 0.3302 0.4318)
							(mid 0.402042 0.402042)
							(end 0.4318 0.3302)
						)
						(arc
							(start 0.4318 -0.3302)
							(mid 0.402042 -0.402042)
							(end 0.3302 -0.4318)
						)
					)
					(width 0)
					(fill yes)
				)
			)
		)
		(pad "2" smd custom
			(at 0 0.762 270)
			(size 0.2159 0.2159)
			(layers "F.Cu" "F.Mask" "F.Paste")
			(net "GND")
			(options
				(clearance outline)
				(anchor circle)
			)
			(primitives
				(gr_poly
					(pts
						(arc
							(start -0.3302 -0.4318)
							(mid -0.402042 -0.402042)
							(end -0.4318 -0.3302)
						)
						(arc
							(start -0.4318 0.3302)
							(mid -0.402042 0.402042)
							(end -0.3302 0.4318)
						)
						(arc
							(start 0.3302 0.4318)
							(mid 0.402042 0.402042)
							(end 0.4318 0.3302)
						)
						(arc
							(start 0.4318 -0.3302)
							(mid 0.402042 -0.402042)
							(end 0.3302 -0.4318)
						)
					)
					(width 0)
					(fill yes)
				)
			)
		)
	)
	(footprint ""
		(layer "F.Cu")
		(at 103.400606 -68.365116 180)
		(property "Reference" "C2D45"
			(at 0 0 180)
			(layer "F.SilkS")
			(hide yes)
			(effects
				(font
					(size 1.27 1.27)
				)
			)
		)
		(property "Value" ""
			(at 0 0 180)
			(layer "F.Fab")
			(effects
				(font
					(size 1.27 1.27)
				)
			)
		)
		(duplicate_pad_numbers_are_jumpers no)
		(fp_poly
			(pts
				(xy -0.4953 -0.2032) (xy 0.4953 -0.2032) (xy 0.4953 1.6002) (xy -0.4953 1.6002)
			)
			(stroke
				(width 0)
				(type default)
			)
			(fill no)
			(layer "F.CrtYd")
		)
		(fp_line
			(start 0.4953 1.6002)
			(end -0.4953 1.6002)
			(stroke
				(width 0.1)
				(type default)
			)
			(layer "F.Fab")
		)
		(fp_line
			(start 0.4953 -0.2032)
			(end 0.4953 1.6002)
			(stroke
				(width 0.1)
				(type default)
			)
			(layer "F.Fab")
		)
		(fp_line
			(start -0.4953 1.6002)
			(end -0.4953 -0.2032)
			(stroke
				(width 0.1)
				(type default)
			)
			(layer "F.Fab")
		)
		(fp_line
			(start -0.4953 -0.2032)
			(end 0.4953 -0.2032)
			(stroke
				(width 0.1)
				(type default)
			)
			(layer "F.Fab")
		)
		(pad "1" smd rect
			(at 0 0 180)
			(size 0.762 0.889)
			(layers "F.Cu" "F.Mask" "F.Paste")
			(net "PVDDQ_GHJ")
		)
		(pad "2" smd rect
			(at 0 1.397 180)
			(size 0.762 0.889)
			(layers "F.Cu" "F.Mask" "F.Paste")
			(net "GND")
		)
		(zone
			(layer "F.Cu")
			(hatch none 0.5)
			(connect_pads
				(clearance 0)
			)
			(min_thickness 0.25)
			(keepout
				(tracks not_allowed)
				(vias allowed)
				(pads allowed)
				(copperpour not_allowed)
				(footprints allowed)
			)
			(placement
				(enabled no)
				(sheetname "")
			)
			(fill
				(thermal_gap 0.5)
				(thermal_bridge_width 0.5)
				(island_removal_mode 0)
			)
			(polygon
				(pts
					(xy 103.781606 -68.809616) (xy 103.019606 -68.809616) (xy 103.019606 -69.317616) (xy 103.781606 -69.317616)
				)
			)
		)
	)
	(footprint ""
		(layer "F.Cu")
		(at 166.8272 -20.828 90)
		(property "Reference" "C4F11"
			(at 2.89433 0.6858 0)
			(unlocked yes)
			(layer "F.SilkS")
			(effects
				(font
					(size 0.7874 0.5842)
					(thickness 0.1524)
				)
				(justify left)
			)
		)
		(property "Value" ""
			(at 0 0 90)
			(layer "F.Fab")
			(effects
				(font
					(size 1.27 1.27)
				)
			)
		)
		(duplicate_pad_numbers_are_jumpers no)
		(fp_line
			(start 2.032 -1.524)
			(end 2.032 1.524)
			(stroke
				(width 0.1524)
				(type default)
			)
			(layer "F.SilkS")
		)
		(fp_line
			(start 1.7272 -1.524)
			(end 2.032 -1.524)
			(stroke
				(width 0.1524)
				(type default)
			)
			(layer "F.SilkS")
		)
		(fp_line
			(start -1.7272 -1.524)
			(end -2.032 -1.524)
			(stroke
				(width 0.1524)
				(type default)
			)
			(layer "F.SilkS")
		)
		(fp_line
			(start -2.032 -1.524)
			(end -2.032 1.524)
			(stroke
				(width 0.1524)
				(type default)
			)
			(layer "F.SilkS")
		)
		(fp_line
			(start 2.2987 -0.2413)
			(end 2.032 -0.2413)
			(stroke
				(width 0.1524)
				(type default)
			)
			(layer "F.SilkS")
		)
		(fp_line
			(start -2.032 -0.2413)
			(end -2.2987 -0.2413)
			(stroke
				(width 0.1524)
				(type default)
			)
			(layer "F.SilkS")
		)
		(fp_line
			(start -2.2987 -0.2413)
			(end -2.2987 7.3533)
			(stroke
				(width 0.1524)
				(type default)
			)
			(layer "F.SilkS")
		)
		(fp_line
			(start 2.032 1.524)
			(end 1.7272 1.524)
			(stroke
				(width 0.1524)
				(type default)
			)
			(layer "F.SilkS")
		)
		(fp_line
			(start -2.032 1.524)
			(end -1.7272 1.524)
			(stroke
				(width 0.1524)
				(type default)
			)
			(layer "F.SilkS")
		)
		(fp_line
			(start 2.2987 7.3533)
			(end 2.2987 -0.2413)
			(stroke
				(width 0.1524)
				(type default)
			)
			(layer "F.SilkS")
		)
		(fp_line
			(start 1.7272 7.3533)
			(end 2.2987 7.3533)
			(stroke
				(width 0.1524)
				(type default)
			)
			(layer "F.SilkS")
		)
		(fp_line
			(start -2.2987 7.3533)
			(end -1.7272 7.3533)
			(stroke
				(width 0.1524)
				(type default)
			)
			(layer "F.SilkS")
		)
		(fp_rect
			(start -2.2987 -0.2413)
			(end 2.2987 7.3533)
			(stroke
				(width 0)
				(type default)
			)
			(fill no)
			(layer "F.CrtYd")
		)
		(fp_line
			(start 2.2987 -0.2413)
			(end 2.2987 7.3533)
			(stroke
				(width 0.1)
				(type default)
			)
			(layer "F.Fab")
		)
		(fp_line
			(start -2.2987 -0.2413)
			(end 2.2987 -0.2413)
			(stroke
				(width 0.1)
				(type default)
			)
			(layer "F.Fab")
		)
		(fp_line
			(start 2.2987 7.3533)
			(end -2.2987 7.3533)
			(stroke
				(width 0.1)
				(type default)
			)
			(layer "F.Fab")
		)
		(fp_line
			(start -2.2987 7.3533)
			(end -2.2987 -0.2413)
			(stroke
				(width 0.1)
				(type default)
			)
			(layer "F.Fab")
		)
		(pad "1" smd rect
			(at 0 0 90)
			(size 2.54 3.048)
			(layers "F.Cu" "F.Mask" "F.Paste")
			(net "PVPP_GHJ")
		)
		(pad "2" smd rect
			(at 0 7.112 90)
			(size 2.54 3.048)
			(layers "F.Cu" "F.Mask" "F.Paste")
			(net "GND")
		)
	)
	(footprint ""
		(layer "F.Cu")
		(at 391.795 -88.2015)
		(property "Reference" "R8D13"
			(at 0 0 0)
			(layer "F.SilkS")
			(hide yes)
			(effects
				(font
					(size 1.27 1.27)
				)
			)
		)
		(property "Value" ""
			(at 0 0 0)
			(layer "F.Fab")
			(effects
				(font
					(size 1.27 1.27)
				)
			)
		)
		(duplicate_pad_numbers_are_jumpers no)
		(fp_poly
			(pts
				(xy -0.2794 -0.1016) (xy 0.2794 -0.1016) (xy 0.2794 0.9906) (xy -0.2794 0.9906)
			)
			(stroke
				(width 0)
				(type default)
			)
			(fill no)
			(layer "F.CrtYd")
		)
		(fp_line
			(start -0.2794 -0.1016)
			(end -0.2794 0.9906)
			(stroke
				(width 0.1)
				(type default)
			)
			(layer "F.Fab")
		)
		(fp_line
			(start -0.2794 0.9906)
			(end 0.2794 0.9906)
			(stroke
				(width 0.1)
				(type default)
			)
			(layer "F.Fab")
		)
		(fp_line
			(start 0.2794 -0.1016)
			(end -0.2794 -0.1016)
			(stroke
				(width 0.1)
				(type default)
			)
			(layer "F.Fab")
		)
		(fp_line
			(start 0.2794 0.9906)
			(end 0.2794 -0.1016)
			(stroke
				(width 0.1)
				(type default)
			)
			(layer "F.Fab")
		)
		(pad "1" smd rect
			(at 0 0)
			(size 0.508 0.508)
			(layers "F.Cu" "F.Mask" "F.Paste")
			(net "P3V3_STBY")
		)
		(pad "2" smd rect
			(at 0 0.889)
			(size 0.508 0.508)
			(layers "F.Cu" "F.Mask" "F.Paste")
			(net "PU_ADR_TIMER_HOLD_OFF_N")
		)
		(zone
			(layer "F.Cu")
			(hatch none 0.5)
			(connect_pads
				(clearance 0)
			)
			(min_thickness 0.25)
			(keepout
				(tracks allowed)
				(vias not_allowed)
				(pads allowed)
				(copperpour not_allowed)
				(footprints allowed)
			)
			(placement
				(enabled no)
				(sheetname "")
			)
			(fill
				(thermal_gap 0.5)
				(thermal_bridge_width 0.5)
				(island_removal_mode 0)
			)
			(polygon
				(pts
					(xy 391.541 -87.9475) (xy 392.049 -87.9475) (xy 392.049 -87.5665) (xy 391.541 -87.5665)
				)
			)
		)
		(zone
			(layer "F.Cu")
			(hatch none 0.5)
			(connect_pads
				(clearance 0)
			)
			(min_thickness 0.25)
			(keepout
				(tracks not_allowed)
				(vias allowed)
				(pads allowed)
				(copperpour not_allowed)
				(footprints allowed)
			)
			(placement
				(enabled no)
				(sheetname "")
			)
			(fill
				(thermal_gap 0.5)
				(thermal_bridge_width 0.5)
				(island_removal_mode 0)
			)
			(polygon
				(pts
					(xy 391.541 -87.5665) (xy 392.049 -87.5665) (xy 392.049 -87.9475) (xy 391.541 -87.9475)
				)
			)
		)
	)
	(footprint ""
		(layer "F.Cu")
		(at 209.296 -52.79898 -90)
		(property "Reference" "R4E13"
			(at 0 0 270)
			(layer "F.SilkS")
			(hide yes)
			(effects
				(font
					(size 1.27 1.27)
				)
			)
		)
		(property "Value" ""
			(at 0 0 270)
			(layer "F.Fab")
			(effects
				(font
					(size 1.27 1.27)
				)
			)
		)
		(duplicate_pad_numbers_are_jumpers no)
		(fp_poly
			(pts
				(xy -0.4953 -0.2032) (xy 0.4953 -0.2032) (xy 0.4953 1.6002) (xy -0.4953 1.6002)
			)
			(stroke
				(width 0)
				(type default)
			)
			(fill no)
			(layer "F.CrtYd")
		)
		(fp_line
			(start -0.4953 1.6002)
			(end -0.4953 -0.2032)
			(stroke
				(width 0.1)
				(type default)
			)
			(layer "F.Fab")
		)
		(fp_line
			(start 0.4953 1.6002)
			(end -0.4953 1.6002)
			(stroke
				(width 0.1)
				(type default)
			)
			(layer "F.Fab")
		)
		(fp_line
			(start -0.4953 -0.2032)
			(end 0.4953 -0.2032)
			(stroke
				(width 0.1)
				(type default)
			)
			(layer "F.Fab")
		)
		(fp_line
			(start 0.4953 -0.2032)
			(end 0.4953 1.6002)
			(stroke
				(width 0.1)
				(type default)
			)
			(layer "F.Fab")
		)
		(pad "1" smd rect
			(at 0 0 270)
			(size 0.762 0.889)
			(layers "F.Cu" "F.Mask" "F.Paste")
			(net "PVCCIN_CPU0")
		)
		(pad "2" smd rect
			(at 0 1.397 270)
			(size 0.762 0.889)
			(layers "F.Cu" "F.Mask" "F.Paste")
			(net "GND")
		)
		(zone
			(layer "F.Cu")
			(hatch none 0.5)
			(connect_pads
				(clearance 0)
			)
			(min_thickness 0.25)
			(keepout
				(tracks not_allowed)
				(vias allowed)
				(pads allowed)
				(copperpour not_allowed)
				(footprints allowed)
			)
			(placement
				(enabled no)
				(sheetname "")
			)
			(fill
				(thermal_gap 0.5)
				(thermal_bridge_width 0.5)
				(island_removal_mode 0)
			)
			(polygon
				(pts
					(xy 208.3435 -53.17998) (xy 208.3435 -52.41798) (xy 208.8515 -52.41798) (xy 208.8515 -53.17998)
				)
			)
		)
		(zone
			(layer "F.Cu")
			(hatch none 0.5)
			(connect_pads
				(clearance 0)
			)
			(min_thickness 0.25)
			(keepout
				(tracks allowed)
				(vias not_allowed)
				(pads allowed)
				(copperpour not_allowed)
				(footprints allowed)
			)
			(placement
				(enabled no)
				(sheetname "")
			)
			(fill
				(thermal_gap 0.5)
				(thermal_bridge_width 0.5)
				(island_removal_mode 0)
			)
			(polygon
				(pts
					(xy 208.3435 -52.41798) (xy 208.8515 -52.41798) (xy 208.8515 -53.17998) (xy 208.3435 -53.17998)
				)
			)
		)
	)
	(footprint ""
		(layer "F.Cu")
		(at 420.103046 -48.968152)
		(property "Reference" "R25W101"
			(at -0.8382 -0.67818 0)
			(unlocked yes)
			(layer "F.SilkS")
			(effects
				(font
					(size 0.4064 0.254)
					(thickness 0.1524)
				)
				(justify left)
			)
		)
		(property "Value" ""
			(at 0 0 0)
			(layer "F.Fab")
			(effects
				(font
					(size 1.27 1.27)
				)
			)
		)
		(duplicate_pad_numbers_are_jumpers no)
		(fp_poly
			(pts
				(xy -0.2794 -0.1016) (xy 0.2794 -0.1016) (xy 0.2794 0.9906) (xy -0.2794 0.9906)
			)
			(stroke
				(width 0)
				(type default)
			)
			(fill no)
			(layer "F.CrtYd")
		)
		(fp_line
			(start -0.2794 -0.1016)
			(end -0.2794 0.9906)
			(stroke
				(width 0.1)
				(type default)
			)
			(layer "F.Fab")
		)
		(fp_line
			(start -0.2794 0.9906)
			(end 0.2794 0.9906)
			(stroke
				(width 0.1)
				(type default)
			)
			(layer "F.Fab")
		)
		(fp_line
			(start 0.2794 -0.1016)
			(end -0.2794 -0.1016)
			(stroke
				(width 0.1)
				(type default)
			)
			(layer "F.Fab")
		)
		(fp_line
			(start 0.2794 0.9906)
			(end 0.2794 -0.1016)
			(stroke
				(width 0.1)
				(type default)
			)
			(layer "F.Fab")
		)
		(pad "1" smd rect
			(at 0 0)
			(size 0.508 0.508)
			(layers "F.Cu" "F.Mask" "F.Paste")
			(net "P3V3_STBY")
		)
		(pad "2" smd rect
			(at 0 0.889)
			(size 0.508 0.508)
			(layers "F.Cu" "F.Mask" "F.Paste")
			(net "BMC_STRAP_BIT17")
		)
		(zone
			(layer "F.Cu")
			(hatch none 0.5)
			(connect_pads
				(clearance 0)
			)
			(min_thickness 0.25)
			(keepout
				(tracks allowed)
				(vias not_allowed)
				(pads allowed)
				(copperpour not_allowed)
				(footprints allowed)
			)
			(placement
				(enabled no)
				(sheetname "")
			)
			(fill
				(thermal_gap 0.5)
				(thermal_bridge_width 0.5)
				(island_removal_mode 0)
			)
			(polygon
				(pts
					(xy 419.849046 -48.714152) (xy 420.357046 -48.714152) (xy 420.357046 -48.333152) (xy 419.849046 -48.333152)
				)
			)
		)
		(zone
			(layer "F.Cu")
			(hatch none 0.5)
			(connect_pads
				(clearance 0)
			)
			(min_thickness 0.25)
			(keepout
				(tracks not_allowed)
				(vias allowed)
				(pads allowed)
				(copperpour not_allowed)
				(footprints allowed)
			)
			(placement
				(enabled no)
				(sheetname "")
			)
			(fill
				(thermal_gap 0.5)
				(thermal_bridge_width 0.5)
				(island_removal_mode 0)
			)
			(polygon
				(pts
					(xy 419.849046 -48.333152) (xy 420.357046 -48.333152) (xy 420.357046 -48.714152) (xy 419.849046 -48.714152)
				)
			)
		)
	)
)
